# S9S_MB_2U (Grand Teton) — schematic netlist excerpt (pin names and nets, part order shuffled) for the footprints in the layout excerpt that follows; sources: Cadence DE-HDL packaged netlist, KiCad conversion of 03242023_DA0F0TMBIJ0_F0T_Motherboard_J_brd_V01_OCP.brd

R1871  Q_RES  10 1% CHIP  pkg 0402LF  page 202 : A = ESPI_LAD0_DATA_IO0 ; B = ESPI_LPC_LAD0_IO0

U243  NC7SB3157  NC7SB3157P6X EMPTY  pkg SMLF  page 165
  B1  = OCP_SFF_NOT_PRSNT_RBT_ARB_IN
  GND  = GND
  B0  = OCP_SFF_RBT_ARB_OUT
  A  = OCP_SFF_RBT_ARB_IN_MUX2
  VCC  = P3V3_AUX
  S  = OCP_SFF_PRSNT_ALL_R1_N

PC384  Q_CAPP  560UF 2.5V 20% OSCON  pkg THLF  page 297 : A = PVCCD_HV_CPU1 ; B = GND

(kicad_pcb
	(version 20260206)
	(generator "pcbnew")
	(generator_version "10.0")
	(general
		(thickness 1.6)
		(legacy_teardrops no)
	)
	(paper "A4")
	(title_block
		(title "03242023_DA0F0TMBIJ0_F0T_Motherboard_J_brd_V01_OCP.brd")
		(comment 1 "Grand Teton / footprints 1199-1201 of 6105")
	)
	(layers
		(0 "F.Cu" signal "TOP")
		(4 "In1.Cu" signal "GND")
		(6 "In2.Cu" signal "IN1")
		(8 "In3.Cu" signal "GND1")
		(10 "In4.Cu" signal "IN2")
		(12 "In5.Cu" signal "GND2")
		(14 "In6.Cu" signal "IN3")
		(16 "In7.Cu" signal "GND3")
		(18 "In8.Cu" signal "VCC")
		(20 "In9.Cu" signal "VCC1")
		(22 "In10.Cu" signal "GND4")
		(24 "In11.Cu" signal "IN4")
		(26 "In12.Cu" signal "GND5")
		(28 "In13.Cu" signal "IN5")
		(30 "In14.Cu" signal "GND6")
		(32 "In15.Cu" signal "IN6")
		(34 "In16.Cu" signal "GND7")
		(2 "B.Cu" signal "BOTTOM")
		(9 "F.Adhes" user "F.Adhesive")
		(11 "B.Adhes" user "B.Adhesive")
		(13 "F.Paste" user "Package Geometry/Pastemask Top")
		(15 "B.Paste" user "Package Geometry/Pastemask Bottom")
		(5 "F.SilkS" user "Ref Des/Silkscreen Top")
		(7 "B.SilkS" user "Ref Des/Silkscreen Bottom")
		(1 "F.Mask" user "Board Geometry/Soldermask Top")
		(3 "B.Mask" user "Board Geometry/Soldermask Bottom")
		(17 "Dwgs.User" user "User.Drawings")
		(19 "Cmts.User" user "User.Comments")
		(21 "Eco1.User" user "User.Eco1")
		(23 "Eco2.User" user "User.Eco2")
		(25 "Edge.Cuts" user "Board Geometry/Outline")
		(27 "Margin" user)
		(31 "F.CrtYd" user "Package Geometry/Place Bound Top")
		(29 "B.CrtYd" user "Package Geometry/Place Bound Bottom")
		(35 "F.Fab" user "Ref Des/Assembly Top")
		(33 "B.Fab" user "Ref Des/Assembly Bottom")
	)
	(footprint ""
		(layer "F.Cu")
		(at 329.124818 -23.803864 -90)
		(property "Reference" "R1871"
			(at 0 0 270)
			(layer "F.SilkS")
			(hide yes)
			(effects
				(font
					(size 1.27 1.27)
				)
			)
		)
		(property "Value" ""
			(at 0 0 270)
			(layer "F.Fab")
			(effects
				(font
					(size 1.27 1.27)
				)
			)
		)
		(duplicate_pad_numbers_are_jumpers no)
		(fp_line
			(start -0.7874 0.4064)
			(end -0.7874 -0.4064)
			(stroke
				(width 0.1524)
				(type default)
			)
			(layer "F.SilkS")
		)
		(fp_line
			(start 0.7874 0.4064)
			(end -0.7874 0.4064)
			(stroke
				(width 0.1524)
				(type default)
			)
			(layer "F.SilkS")
		)
		(fp_line
			(start -0.7874 -0.4064)
			(end 0.7874 -0.4064)
			(stroke
				(width 0.1524)
				(type default)
			)
			(layer "F.SilkS")
		)
		(fp_line
			(start 0.7874 -0.4064)
			(end 0.7874 0.4064)
			(stroke
				(width 0.1524)
				(type default)
			)
			(layer "F.SilkS")
		)
		(fp_line
			(start -0.67945 0.3048)
			(end -0.67945 -0.305054)
			(stroke
				(width 0.1)
				(type default)
			)
			(layer "F.Fab")
		)
		(fp_line
			(start -0.12065 0.3048)
			(end -0.67945 0.3048)
			(stroke
				(width 0.1)
				(type default)
			)
			(layer "F.Fab")
		)
		(fp_line
			(start 0.120396 0.3048)
			(end 0.120396 0.2794)
			(stroke
				(width 0.1)
				(type default)
			)
			(layer "F.Fab")
		)
		(fp_line
			(start 0.67945 0.3048)
			(end 0.120396 0.3048)
			(stroke
				(width 0.1)
				(type default)
			)
			(layer "F.Fab")
		)
		(fp_line
			(start -0.12065 0.2794)
			(end -0.12065 0.3048)
			(stroke
				(width 0.1)
				(type default)
			)
			(layer "F.Fab")
		)
		(fp_line
			(start 0.120396 0.2794)
			(end -0.12065 0.2794)
			(stroke
				(width 0.1)
				(type default)
			)
			(layer "F.Fab")
		)
		(fp_line
			(start -0.12065 -0.2794)
			(end 0.12065 -0.2794)
			(stroke
				(width 0.1)
				(type default)
			)
			(layer "F.Fab")
		)
		(fp_line
			(start 0.12065 -0.2794)
			(end 0.12065 -0.3048)
			(stroke
				(width 0.1)
				(type default)
			)
			(layer "F.Fab")
		)
		(fp_line
			(start 0.12065 -0.3048)
			(end 0.67945 -0.3048)
			(stroke
				(width 0.1)
				(type default)
			)
			(layer "F.Fab")
		)
		(fp_line
			(start 0.67945 -0.3048)
			(end 0.67945 0.3048)
			(stroke
				(width 0.1)
				(type default)
			)
			(layer "F.Fab")
		)
		(fp_line
			(start -0.67945 -0.305054)
			(end -0.12065 -0.305054)
			(stroke
				(width 0.1)
				(type default)
			)
			(layer "F.Fab")
		)
		(fp_line
			(start -0.12065 -0.305054)
			(end -0.12065 -0.2794)
			(stroke
				(width 0.1)
				(type default)
			)
			(layer "F.Fab")
		)
		(pad "1" smd circle
			(at -0.40005 0 270)
			(size 0 0)
			(layers "F.Cu" "F.Mask" "F.Paste")
			(net "ESPI_LAD0_DATA_IO0")
		)
		(pad "2" smd circle
			(at 0.40005 0 270)
			(size 0 0)
			(layers "F.Cu" "F.Mask" "F.Paste")
			(net "ESPI_LPC_LAD0_IO0")
		)
	)
	(footprint ""
		(layer "F.Cu")
		(at 68.644008 -171.77004 90)
		(property "Reference" "PC384"
			(at 0 0 90)
			(layer "F.SilkS")
			(hide yes)
			(effects
				(font
					(size 1.27 1.27)
				)
			)
		)
		(property "Value" ""
			(at 0 0 90)
			(layer "F.Fab")
			(effects
				(font
					(size 1.27 1.27)
				)
			)
		)
		(duplicate_pad_numbers_are_jumpers no)
		(fp_line
			(start 2.750058 0.999998)
			(end -2.750058 0.999998)
			(stroke
				(width 0.1524)
				(type default)
			)
			(layer "F.SilkS")
		)
		(fp_circle
			(center 0 0.999998)
			(end 0 3.750056)
			(stroke
				(width 0.1524)
				(type default)
			)
			(fill no)
			(layer "F.SilkS")
		)
		(fp_poly
			(pts
				(arc
					(start 2.750058 0.999998)
					(mid 0 3.750056)
					(end -2.750058 0.999998)
				)
			)
			(stroke
				(width 0)
				(type default)
			)
			(fill yes)
			(layer "F.SilkS")
		)
		(fp_circle
			(center 0 0.999998)
			(end 0 3.750056)
			(stroke
				(width 0.1)
				(type default)
			)
			(fill no)
			(layer "F.Fab")
		)
		(pad "1" thru_hole rect
			(at 0 0 90)
			(size 1.5748 1.5748)
			(drill 1.0668)
			(layers "*.Cu" "*.Mask")
			(remove_unused_layers no)
			(net "PVCCD_HV_CPU1")
			(clearance 0)
			(padstack
				(mode front_inner_back)
				(layer "Inner"
					(shape circle)
					(size 1.5748 1.5748)
					(clearance 0)
				)
				(layer "B.Cu"
					(shape rect)
					(size 1.5748 1.5748)
					(clearance 0)
				)
			)
		)
		(pad "2" thru_hole circle
			(at 0 1.999996 90)
			(size 1.5748 1.5748)
			(drill 1.0668)
			(layers "*.Cu" "*.Mask")
			(remove_unused_layers no)
			(net "GND")
			(clearance 0)
		)
	)
	(footprint ""
		(layer "F.Cu")
		(at 145.59534 -36.761928)
		(property "Reference" "U243"
			(at -1.016 -1.80213 0)
			(unlocked yes)
			(layer "F.SilkS")
			(effects
				(font
					(size 0.7874 0.5842)
					(thickness 0.1524)
				)
			)
		)
		(property "Value" ""
			(at 0 0 0)
			(layer "F.Fab")
			(effects
				(font
					(size 1.27 1.27)
				)
			)
		)
		(duplicate_pad_numbers_are_jumpers no)
		(fp_line
			(start -1.7272 1.1176)
			(end -1.7272 -1.1176)
			(stroke
				(width 0.1524)
				(type default)
			)
			(layer "F.SilkS")
		)
		(fp_line
			(start -0.254 -1.1176)
			(end -1.7272 -1.1176)
			(stroke
				(width 0.1524)
				(type default)
			)
			(layer "F.SilkS")
		)
		(fp_line
			(start 0 -0.7366)
			(end -0.254 -1.1176)
			(stroke
				(width 0.1524)
				(type default)
			)
			(layer "F.SilkS")
		)
		(fp_line
			(start 0.254 -1.1176)
			(end 0 -0.7366)
			(stroke
				(width 0.1524)
				(type default)
			)
			(layer "F.SilkS")
		)
		(fp_line
			(start 1.7272 -1.1176)
			(end 0.254 -1.1176)
			(stroke
				(width 0.1524)
				(type default)
			)
			(layer "F.SilkS")
		)
		(fp_line
			(start 1.7272 -1.1176)
			(end 1.7272 1.1176)
			(stroke
				(width 0.1524)
				(type default)
			)
			(layer "F.SilkS")
		)
		(fp_line
			(start 1.7272 1.1176)
			(end -1.7272 1.1176)
			(stroke
				(width 0.1524)
				(type default)
			)
			(layer "F.SilkS")
		)
		(fp_poly
			(pts
				(xy -2.7178 -0.268986) (xy -2.7178 -1.030986) (xy -1.9558 -0.649986)
			)
			(stroke
				(width 0)
				(type default)
			)
			(fill yes)
			(layer "F.SilkS")
		)
		(fp_line
			(start -1.5748 -1.1176)
			(end -1.5748 1.1176)
			(stroke
				(width 0.1)
				(type default)
			)
			(layer "F.Fab")
		)
		(fp_line
			(start -1.5748 1.1176)
			(end 1.5748 1.1176)
			(stroke
				(width 0.1)
				(type default)
			)
			(layer "F.Fab")
		)
		(fp_line
			(start 1.5748 -1.1176)
			(end -1.5748 -1.1176)
			(stroke
				(width 0.1)
				(type default)
			)
			(layer "F.Fab")
		)
		(fp_line
			(start 1.5748 1.1176)
			(end 1.5748 -1.1176)
			(stroke
				(width 0.1)
				(type default)
			)
			(layer "F.Fab")
		)
		(fp_poly
			(pts
				(xy -1.9558 -0.649986) (xy -2.7178 -0.268986) (xy -2.7178 -1.030986)
			)
			(stroke
				(width 0)
				(type default)
			)
			(fill yes)
			(layer "F.Fab")
		)
		(pad "1" smd rect
			(at -0.999998 -0.649986 270)
			(size 0.3556 1.1176)
			(layers "F.Cu" "F.Mask" "F.Paste")
			(net "OCP_SFF_NOT_PRSNT_RBT_ARB_IN")
		)
		(pad "2" smd rect
			(at -0.999998 0 270)
			(size 0.3556 1.1176)
			(layers "F.Cu" "F.Mask" "F.Paste")
			(net "GND")
		)
		(pad "3" smd rect
			(at -0.999998 0.649986 270)
			(size 0.3556 1.1176)
			(layers "F.Cu" "F.Mask" "F.Paste")
			(net "OCP_SFF_RBT_ARB_OUT")
		)
		(pad "4" smd rect
			(at 0.999998 0.649986 270)
			(size 0.3556 1.1176)
			(layers "F.Cu" "F.Mask" "F.Paste")
			(net "OCP_SFF_RBT_ARB_IN_MUX2")
		)
		(pad "5" smd rect
			(at 0.999998 0 270)
			(size 0.3556 1.1176)
			(layers "F.Cu" "F.Mask" "F.Paste")
			(net "P3V3_AUX")
		)
		(pad "6" smd rect
			(at 0.999998 -0.649986 270)
			(size 0.3556 1.1176)
			(layers "F.Cu" "F.Mask" "F.Paste")
			(net "OCP_SFF_PRSNT_ALL_R1_N")
		)
	)
)
